# T6G (Grand Teton) — schematic netlist excerpt (pin names and nets, part order shuffled) for the footprints in the layout excerpt that follows; sources: Cadence DE-HDL packaged netlist, KiCad conversion of 04192023_DAF0TMB3IC0_F0TG_MB_C_brd_V02_OCP.brd

R454  Q_RES  10K 5% CHIP  pkg 0402LF  page 29 : A = PVDD18_S5_P0 ; B = SCM_USB_OC_BUF_N
R430  Q_RES  0 5% CHIP  pkg 0402LF  page 28 : A = SMB_CPU0_4_R_SCL ; B = SMB_CPU0_4_SCL

(kicad_pcb
	(version 20260206)
	(generator "pcbnew")
	(generator_version "10.0")
	(general
		(thickness 1.6)
		(legacy_teardrops no)
	)
	(paper "A4")
	(title_block
		(title "04192023_DAF0TMB3IC0_F0TG_MB_C_brd_V02_OCP.brd")
		(comment 1 "Grand Teton / footprints 6222-6223 of 8354")
	)
	(layers
		(0 "F.Cu" signal "TOP")
		(4 "In1.Cu" signal "GND")
		(6 "In2.Cu" signal "IN1")
		(8 "In3.Cu" signal "GND1")
		(10 "In4.Cu" signal "IN2")
		(12 "In5.Cu" signal "GND2")
		(14 "In6.Cu" signal "IN3")
		(16 "In7.Cu" signal "GND3")
		(18 "In8.Cu" signal "VCC")
		(20 "In9.Cu" signal "VCC1")
		(22 "In10.Cu" signal "GND4")
		(24 "In11.Cu" signal "IN4")
		(26 "In12.Cu" signal "GND5")
		(28 "In13.Cu" signal "IN5")
		(30 "In14.Cu" signal "GND6")
		(32 "In15.Cu" signal "IN6")
		(34 "In16.Cu" signal "GND7")
		(2 "B.Cu" signal "BOTTOM")
		(9 "F.Adhes" user "F.Adhesive")
		(11 "B.Adhes" user "B.Adhesive")
		(13 "F.Paste" user "Package Geometry/Pastemask Top")
		(15 "B.Paste" user "Package Geometry/Pastemask Bottom")
		(5 "F.SilkS" user "Ref Des/Silkscreen Top")
		(7 "B.SilkS" user "Ref Des/Silkscreen Bottom")
		(1 "F.Mask" user "Board Geometry/Soldermask Top")
		(3 "B.Mask" user "Board Geometry/Soldermask Bottom")
		(17 "Dwgs.User" user "User.Drawings")
		(19 "Cmts.User" user "User.Comments")
		(21 "Eco1.User" user "User.Eco1")
		(23 "Eco2.User" user "User.Eco2")
		(25 "Edge.Cuts" user "Board Geometry/Outline")
		(27 "Margin" user)
		(31 "F.CrtYd" user "Package Geometry/Place Bound Top")
		(29 "B.CrtYd" user "Package Geometry/Place Bound Bottom")
		(35 "F.Fab" user "Ref Des/Assembly Top")
		(33 "B.Fab" user "Ref Des/Assembly Bottom")
	)
	(footprint ""
		(layer "B.Cu")
		(at 404.070058 -319.748916 -90)
		(property "Reference" "R430"
			(at 0 0 90)
			(layer "B.SilkS")
			(hide yes)
			(effects
				(font
					(size 1.27 1.27)
				)
				(justify mirror)
			)
		)
		(property "Value" ""
			(at 0 0 90)
			(layer "B.Fab")
			(effects
				(font
					(size 1.27 1.27)
				)
				(justify mirror)
			)
		)
		(duplicate_pad_numbers_are_jumpers no)
		(fp_line
			(start -0.7874 0.4064)
			(end 0.7874 0.4064)
			(stroke
				(width 0.1524)
				(type default)
			)
			(layer "B.SilkS")
		)
		(fp_line
			(start 0.7874 0.4064)
			(end 0.7874 -0.4064)
			(stroke
				(width 0.1524)
				(type default)
			)
			(layer "B.SilkS")
		)
		(fp_line
			(start -0.7874 -0.4064)
			(end -0.7874 0.4064)
			(stroke
				(width 0.1524)
				(type default)
			)
			(layer "B.SilkS")
		)
		(fp_line
			(start 0.7874 -0.4064)
			(end -0.7874 -0.4064)
			(stroke
				(width 0.1524)
				(type default)
			)
			(layer "B.SilkS")
		)
		(fp_line
			(start -0.67945 0.3048)
			(end -0.120396 0.3048)
			(stroke
				(width 0.1)
				(type default)
			)
			(layer "B.Fab")
		)
		(fp_line
			(start -0.120396 0.3048)
			(end -0.120396 0.2794)
			(stroke
				(width 0.1)
				(type default)
			)
			(layer "B.Fab")
		)
		(fp_line
			(start 0.12065 0.3048)
			(end 0.67945 0.3048)
			(stroke
				(width 0.1)
				(type default)
			)
			(layer "B.Fab")
		)
		(fp_line
			(start 0.67945 0.3048)
			(end 0.67945 -0.305054)
			(stroke
				(width 0.1)
				(type default)
			)
			(layer "B.Fab")
		)
		(fp_line
			(start -0.120396 0.2794)
			(end 0.12065 0.2794)
			(stroke
				(width 0.1)
				(type default)
			)
			(layer "B.Fab")
		)
		(fp_line
			(start 0.12065 0.2794)
			(end 0.12065 0.3048)
			(stroke
				(width 0.1)
				(type default)
			)
			(layer "B.Fab")
		)
		(fp_line
			(start -0.12065 -0.2794)
			(end -0.12065 -0.3048)
			(stroke
				(width 0.1)
				(type default)
			)
			(layer "B.Fab")
		)
		(fp_line
			(start 0.12065 -0.2794)
			(end -0.12065 -0.2794)
			(stroke
				(width 0.1)
				(type default)
			)
			(layer "B.Fab")
		)
		(fp_line
			(start -0.67945 -0.3048)
			(end -0.67945 0.3048)
			(stroke
				(width 0.1)
				(type default)
			)
			(layer "B.Fab")
		)
		(fp_line
			(start -0.12065 -0.3048)
			(end -0.67945 -0.3048)
			(stroke
				(width 0.1)
				(type default)
			)
			(layer "B.Fab")
		)
		(fp_line
			(start 0.12065 -0.305054)
			(end 0.12065 -0.2794)
			(stroke
				(width 0.1)
				(type default)
			)
			(layer "B.Fab")
		)
		(fp_line
			(start 0.67945 -0.305054)
			(end 0.12065 -0.305054)
			(stroke
				(width 0.1)
				(type default)
			)
			(layer "B.Fab")
		)
		(pad "1" smd circle
			(at 0.40005 0 90)
			(size 0 0)
			(layers "B.Cu" "B.Mask" "B.Paste")
			(net "SMB_CPU0_4_R_SCL")
		)
		(pad "2" smd circle
			(at -0.40005 0 90)
			(size 0 0)
			(layers "B.Cu" "B.Mask" "B.Paste")
			(net "SMB_CPU0_4_SCL")
		)
	)
	(footprint ""
		(layer "B.Cu")
		(at 397.788892 -202.324208)
		(property "Reference" "R454"
			(at 0 0 0)
			(layer "B.SilkS")
			(hide yes)
			(effects
				(font
					(size 1.27 1.27)
				)
				(justify mirror)
			)
		)
		(property "Value" ""
			(at 0 0 0)
			(layer "B.Fab")
			(effects
				(font
					(size 1.27 1.27)
				)
				(justify mirror)
			)
		)
		(duplicate_pad_numbers_are_jumpers no)
		(fp_line
			(start -0.7874 -0.4064)
			(end -0.7874 0.4064)
			(stroke
				(width 0.1524)
				(type default)
			)
			(layer "B.SilkS")
		)
		(fp_line
			(start -0.7874 0.4064)
			(end 0.7874 0.4064)
			(stroke
				(width 0.1524)
				(type default)
			)
			(layer "B.SilkS")
		)
		(fp_line
			(start 0.7874 -0.4064)
			(end -0.7874 -0.4064)
			(stroke
				(width 0.1524)
				(type default)
			)
			(layer "B.SilkS")
		)
		(fp_line
			(start 0.7874 0.4064)
			(end 0.7874 -0.4064)
			(stroke
				(width 0.1524)
				(type default)
			)
			(layer "B.SilkS")
		)
		(fp_line
			(start -0.67945 -0.3048)
			(end -0.67945 0.3048)
			(stroke
				(width 0.1)
				(type default)
			)
			(layer "B.Fab")
		)
		(fp_line
			(start -0.67945 0.3048)
			(end -0.120396 0.3048)
			(stroke
				(width 0.1)
				(type default)
			)
			(layer "B.Fab")
		)
		(fp_line
			(start -0.12065 -0.3048)
			(end -0.67945 -0.3048)
			(stroke
				(width 0.1)
				(type default)
			)
			(layer "B.Fab")
		)
		(fp_line
			(start -0.12065 -0.2794)
			(end -0.12065 -0.3048)
			(stroke
				(width 0.1)
				(type default)
			)
			(layer "B.Fab")
		)
		(fp_line
			(start -0.120396 0.2794)
			(end 0.12065 0.2794)
			(stroke
				(width 0.1)
				(type default)
			)
			(layer "B.Fab")
		)
		(fp_line
			(start -0.120396 0.3048)
			(end -0.120396 0.2794)
			(stroke
				(width 0.1)
				(type default)
			)
			(layer "B.Fab")
		)
		(fp_line
			(start 0.12065 -0.305054)
			(end 0.12065 -0.2794)
			(stroke
				(width 0.1)
				(type default)
			)
			(layer "B.Fab")
		)
		(fp_line
			(start 0.12065 -0.2794)
			(end -0.12065 -0.2794)
			(stroke
				(width 0.1)
				(type default)
			)
			(layer "B.Fab")
		)
		(fp_line
			(start 0.12065 0.2794)
			(end 0.12065 0.3048)
			(stroke
				(width 0.1)
				(type default)
			)
			(layer "B.Fab")
		)
		(fp_line
			(start 0.12065 0.3048)
			(end 0.67945 0.3048)
			(stroke
				(width 0.1)
				(type default)
			)
			(layer "B.Fab")
		)
		(fp_line
			(start 0.67945 -0.305054)
			(end 0.12065 -0.305054)
			(stroke
				(width 0.1)
				(type default)
			)
			(layer "B.Fab")
		)
		(fp_line
			(start 0.67945 0.3048)
			(end 0.67945 -0.305054)
			(stroke
				(width 0.1)
				(type default)
			)
			(layer "B.Fab")
		)
		(pad "1" smd circle
			(at 0.40005 0 180)
			(size 0 0)
			(layers "B.Cu" "B.Mask" "B.Paste")
			(net "PVDD18_S5_P0")
		)
		(pad "2" smd circle
			(at -0.40005 0 180)
			(size 0 0)
			(layers "B.Cu" "B.Mask" "B.Paste")
			(net "SCM_USB_OC_BUF_N")
		)
	)
)
